(kicad_pcb
	(version 20260206)
	(generator "pcbnew")
	(generator_version "10.0")
	(general
		(thickness 1.6)
		(legacy_teardrops no)
	)
	(paper "A4")
	(title_block
		(title "01162023_DA0F0TEBIF0_F0T_Expander_BD_F_brd_V02_OCP.brd")
		(comment 1 "Grand Teton / footprints 9275-9282 of 9728")
	)
	(layers
		(0 "F.Cu" signal "TOP")
		(4 "In1.Cu" signal "GND")
		(6 "In2.Cu" signal "VCC")
		(8 "In3.Cu" signal "VCC1")
		(10 "In4.Cu" signal "GND1")
		(12 "In5.Cu" signal "IN1")
		(14 "In6.Cu" signal "GND2")
		(16 "In7.Cu" signal "IN2")
		(18 "In8.Cu" signal "GND3")
		(20 "In9.Cu" signal "IN3")
		(22 "In10.Cu" signal "GND4")
		(24 "In11.Cu" signal "IN4")
		(26 "In12.Cu" signal "GND5")
		(28 "In13.Cu" signal "IN5")
		(30 "In14.Cu" signal "GND6")
		(32 "In15.Cu" signal "IN6")
		(34 "In16.Cu" signal "GND7")
		(2 "B.Cu" signal "BOTTOM")
		(9 "F.Adhes" user "F.Adhesive")
		(11 "B.Adhes" user "B.Adhesive")
		(13 "F.Paste" user "Package Geometry/Pastemask Top")
		(15 "B.Paste" user "Package Geometry/Pastemask Bottom")
		(5 "F.SilkS" user "Ref Des/Silkscreen Top")
		(7 "B.SilkS" user "Ref Des/Silkscreen Bottom")
		(1 "F.Mask" user "Board Geometry/Soldermask Top")
		(3 "B.Mask" user "Board Geometry/Soldermask Bottom")
		(17 "Dwgs.User" user "User.Drawings")
		(19 "Cmts.User" user "User.Comments")
		(21 "Eco1.User" user "User.Eco1")
		(23 "Eco2.User" user "User.Eco2")
		(25 "Edge.Cuts" user "Board Geometry/Outline")
		(27 "Margin" user)
		(31 "F.CrtYd" user "Package Geometry/Place Bound Top")
		(29 "B.CrtYd" user "Package Geometry/Place Bound Bottom")
		(35 "F.Fab" user "Ref Des/Assembly Top")
		(33 "B.Fab" user "Ref Des/Assembly Bottom")
	)
	(footprint ""
		(layer "B.Cu")
		(at 217.664538 -275.315172)
		(property "Reference" "C4276"
			(at 0 0 0)
			(layer "B.SilkS")
			(hide yes)
			(effects
				(font
					(size 1.27 1.27)
				)
				(justify mirror)
			)
		)
		(property "Value" ""
			(at 0 0 0)
			(layer "B.Fab")
			(effects
				(font
					(size 1.27 1.27)
				)
				(justify mirror)
			)
		)
		(duplicate_pad_numbers_are_jumpers no)
		(fp_line
			(start -1.2954 -0.5842)
			(end -1.2954 0.5842)
			(stroke
				(width 0.1524)
				(type default)
			)
			(layer "B.SilkS")
		)
		(fp_line
			(start -1.2954 0.5842)
			(end 1.2954 0.5842)
			(stroke
				(width 0.1524)
				(type default)
			)
			(layer "B.SilkS")
		)
		(fp_line
			(start 1.2954 -0.5842)
			(end -1.2954 -0.5842)
			(stroke
				(width 0.1524)
				(type default)
			)
			(layer "B.SilkS")
		)
		(fp_line
			(start 1.2954 0.5842)
			(end 1.2954 -0.5842)
			(stroke
				(width 0.1524)
				(type default)
			)
			(layer "B.SilkS")
		)
		(fp_line
			(start -1.1938 -0.4064)
			(end -1.1938 0.4064)
			(stroke
				(width 0.1)
				(type default)
			)
			(layer "B.Fab")
		)
		(fp_line
			(start -1.1938 0.4064)
			(end -0.8636 0.4064)
			(stroke
				(width 0.1)
				(type default)
			)
			(layer "B.Fab")
		)
		(fp_line
			(start -0.8636 -0.4572)
			(end -0.8636 -0.4064)
			(stroke
				(width 0.1)
				(type default)
			)
			(layer "B.Fab")
		)
		(fp_line
			(start -0.8636 -0.4064)
			(end -1.1938 -0.4064)
			(stroke
				(width 0.1)
				(type default)
			)
			(layer "B.Fab")
		)
		(fp_line
			(start -0.8636 0.4064)
			(end -0.8636 0.4572)
			(stroke
				(width 0.1)
				(type default)
			)
			(layer "B.Fab")
		)
		(fp_line
			(start -0.8636 0.4572)
			(end 0.8636 0.4572)
			(stroke
				(width 0.1)
				(type default)
			)
			(layer "B.Fab")
		)
		(fp_line
			(start 0.8636 -0.4572)
			(end -0.8636 -0.4572)
			(stroke
				(width 0.1)
				(type default)
			)
			(layer "B.Fab")
		)
		(fp_line
			(start 0.8636 -0.4064)
			(end 0.8636 -0.4572)
			(stroke
				(width 0.1)
				(type default)
			)
			(layer "B.Fab")
		)
		(fp_line
			(start 0.8636 0.4064)
			(end 1.1938 0.4064)
			(stroke
				(width 0.1)
				(type default)
			)
			(layer "B.Fab")
		)
		(fp_line
			(start 0.8636 0.4572)
			(end 0.8636 0.4064)
			(stroke
				(width 0.1)
				(type default)
			)
			(layer "B.Fab")
		)
		(fp_line
			(start 1.1938 -0.4064)
			(end 0.8636 -0.4064)
			(stroke
				(width 0.1)
				(type default)
			)
			(layer "B.Fab")
		)
		(fp_line
			(start 1.1938 0.4064)
			(end 1.1938 -0.4064)
			(stroke
				(width 0.1)
				(type default)
			)
			(layer "B.Fab")
		)
		(pad "1" smd rect
			(at 0.7366 0 270)
			(size 0.7112 0.8128)
			(layers "B.Cu" "B.Mask" "B.Paste")
			(net "P1V25_PEX1")
		)
		(pad "2" smd rect
			(at -0.7366 0 270)
			(size 0.7112 0.8128)
			(layers "B.Cu" "B.Mask" "B.Paste")
			(net "GND")
		)
	)
	(footprint ""
		(layer "B.Cu")
		(at 140.774166 -223.315276 180)
		(property "Reference" "C2783"
			(at 0 0 0)
			(layer "B.SilkS")
			(hide yes)
			(effects
				(font
					(size 1.27 1.27)
				)
				(justify mirror)
			)
		)
		(property "Value" ""
			(at 0 0 0)
			(layer "B.Fab")
			(effects
				(font
					(size 1.27 1.27)
				)
				(justify mirror)
			)
		)
		(duplicate_pad_numbers_are_jumpers no)
		(fp_line
			(start 0.7874 0.4064)
			(end 0.7874 -0.4064)
			(stroke
				(width 0.1524)
				(type default)
			)
			(layer "B.SilkS")
		)
		(fp_line
			(start 0.7874 -0.4064)
			(end -0.7874 -0.4064)
			(stroke
				(width 0.1524)
				(type default)
			)
			(layer "B.SilkS")
		)
		(fp_line
			(start -0.7874 0.4064)
			(end 0.7874 0.4064)
			(stroke
				(width 0.1524)
				(type default)
			)
			(layer "B.SilkS")
		)
		(fp_line
			(start -0.7874 -0.4064)
			(end -0.7874 0.4064)
			(stroke
				(width 0.1524)
				(type default)
			)
			(layer "B.SilkS")
		)
		(fp_line
			(start 0.67945 0.3048)
			(end 0.67945 -0.305054)
			(stroke
				(width 0.1)
				(type default)
			)
			(layer "B.Fab")
		)
		(fp_line
			(start 0.67945 -0.305054)
			(end 0.12065 -0.305054)
			(stroke
				(width 0.1)
				(type default)
			)
			(layer "B.Fab")
		)
		(fp_line
			(start 0.12065 0.3048)
			(end 0.67945 0.3048)
			(stroke
				(width 0.1)
				(type default)
			)
			(layer "B.Fab")
		)
		(fp_line
			(start 0.12065 0.2794)
			(end 0.12065 0.3048)
			(stroke
				(width 0.1)
				(type default)
			)
			(layer "B.Fab")
		)
		(fp_line
			(start 0.12065 -0.2794)
			(end -0.12065 -0.2794)
			(stroke
				(width 0.1)
				(type default)
			)
			(layer "B.Fab")
		)
		(fp_line
			(start 0.12065 -0.305054)
			(end 0.12065 -0.2794)
			(stroke
				(width 0.1)
				(type default)
			)
			(layer "B.Fab")
		)
		(fp_line
			(start -0.120396 0.3048)
			(end -0.120396 0.2794)
			(stroke
				(width 0.1)
				(type default)
			)
			(layer "B.Fab")
		)
		(fp_line
			(start -0.120396 0.2794)
			(end 0.12065 0.2794)
			(stroke
				(width 0.1)
				(type default)
			)
			(layer "B.Fab")
		)
		(fp_line
			(start -0.12065 -0.2794)
			(end -0.12065 -0.3048)
			(stroke
				(width 0.1)
				(type default)
			)
			(layer "B.Fab")
		)
		(fp_line
			(start -0.12065 -0.3048)
			(end -0.67945 -0.3048)
			(stroke
				(width 0.1)
				(type default)
			)
			(layer "B.Fab")
		)
		(fp_line
			(start -0.67945 0.3048)
			(end -0.120396 0.3048)
			(stroke
				(width 0.1)
				(type default)
			)
			(layer "B.Fab")
		)
		(fp_line
			(start -0.67945 -0.3048)
			(end -0.67945 0.3048)
			(stroke
				(width 0.1)
				(type default)
			)
			(layer "B.Fab")
		)
		(pad "1" smd circle
			(at 0.40005 0)
			(size 0 0)
			(layers "B.Cu" "B.Mask" "B.Paste")
			(net "GND")
		)
		(pad "2" smd circle
			(at -0.40005 0)
			(size 0 0)
			(layers "B.Cu" "B.Mask" "B.Paste")
			(net "P1V8_PEX")
		)
	)
	(footprint ""
		(layer "B.Cu")
		(at 231.396286 -256.9845)
		(property "Reference" "C4351"
			(at 0 0 0)
			(layer "B.SilkS")
			(hide yes)
			(effects
				(font
					(size 1.27 1.27)
				)
				(justify mirror)
			)
		)
		(property "Value" ""
			(at 0 0 0)
			(layer "B.Fab")
			(effects
				(font
					(size 1.27 1.27)
				)
				(justify mirror)
			)
		)
		(duplicate_pad_numbers_are_jumpers no)
		(fp_line
			(start -0.299974 -0.150114)
			(end -0.299974 0.150114)
			(stroke
				(width 0.1)
				(type default)
			)
			(layer "B.Fab")
		)
		(fp_line
			(start -0.299974 0.150114)
			(end 0.299974 0.150114)
			(stroke
				(width 0.1)
				(type default)
			)
			(layer "B.Fab")
		)
		(fp_line
			(start 0.299974 -0.150114)
			(end -0.299974 -0.150114)
			(stroke
				(width 0.1)
				(type default)
			)
			(layer "B.Fab")
		)
		(fp_line
			(start 0.299974 0.150114)
			(end 0.299974 -0.150114)
			(stroke
				(width 0.1)
				(type default)
			)
			(layer "B.Fab")
		)
		(pad "1" smd rect
			(at 0.2667 0 180)
			(size 0.3048 0.381)
			(layers "B.Cu" "B.Mask" "B.Paste")
			(net "P1V25_SERDES_VDDPLL_PEX2")
		)
		(pad "2" smd rect
			(at -0.2667 0 180)
			(size 0.3048 0.381)
			(layers "B.Cu" "B.Mask" "B.Paste")
			(net "GND")
		)
	)
	(footprint ""
		(layer "B.Cu")
		(at 45.864272 -143.608552 180)
		(property "Reference" "C848"
			(at 0 0 0)
			(layer "B.SilkS")
			(hide yes)
			(effects
				(font
					(size 1.27 1.27)
				)
				(justify mirror)
			)
		)
		(property "Value" ""
			(at 0 0 0)
			(layer "B.Fab")
			(effects
				(font
					(size 1.27 1.27)
				)
				(justify mirror)
			)
		)
		(duplicate_pad_numbers_are_jumpers no)
		(fp_line
			(start 0.299974 0.150114)
			(end 0.299974 -0.150114)
			(stroke
				(width 0.1)
				(type default)
			)
			(layer "B.Fab")
		)
		(fp_line
			(start 0.299974 -0.150114)
			(end -0.299974 -0.150114)
			(stroke
				(width 0.1)
				(type default)
			)
			(layer "B.Fab")
		)
		(fp_line
			(start -0.299974 0.150114)
			(end 0.299974 0.150114)
			(stroke
				(width 0.1)
				(type default)
			)
			(layer "B.Fab")
		)
		(fp_line
			(start -0.299974 -0.150114)
			(end -0.299974 0.150114)
			(stroke
				(width 0.1)
				(type default)
			)
			(layer "B.Fab")
		)
		(pad "1" smd rect
			(at 0.2667 0)
			(size 0.3048 0.381)
			(layers "B.Cu" "B.Mask" "B.Paste")
			(net "P12V_NIC0")
		)
		(pad "2" smd rect
			(at -0.2667 0)
			(size 0.3048 0.381)
			(layers "B.Cu" "B.Mask" "B.Paste")
			(net "GND")
		)
	)
	(footprint ""
		(layer "B.Cu")
		(at 189.371478 -114.592608)
		(property "Reference" "C898"
			(at 0 0 0)
			(layer "B.SilkS")
			(hide yes)
			(effects
				(font
					(size 1.27 1.27)
				)
				(justify mirror)
			)
		)
		(property "Value" ""
			(at 0 0 0)
			(layer "B.Fab")
			(effects
				(font
					(size 1.27 1.27)
				)
				(justify mirror)
			)
		)
		(duplicate_pad_numbers_are_jumpers no)
		(fp_line
			(start -0.7874 -0.4064)
			(end -0.7874 0.4064)
			(stroke
				(width 0.1524)
				(type default)
			)
			(layer "B.SilkS")
		)
		(fp_line
			(start -0.7874 0.4064)
			(end 0.7874 0.4064)
			(stroke
				(width 0.1524)
				(type default)
			)
			(layer "B.SilkS")
		)
		(fp_line
			(start 0.7874 -0.4064)
			(end -0.7874 -0.4064)
			(stroke
				(width 0.1524)
				(type default)
			)
			(layer "B.SilkS")
		)
		(fp_line
			(start 0.7874 0.4064)
			(end 0.7874 -0.4064)
			(stroke
				(width 0.1524)
				(type default)
			)
			(layer "B.SilkS")
		)
		(fp_line
			(start -0.67945 -0.3048)
			(end -0.67945 0.3048)
			(stroke
				(width 0.1)
				(type default)
			)
			(layer "B.Fab")
		)
		(fp_line
			(start -0.67945 0.3048)
			(end -0.120396 0.3048)
			(stroke
				(width 0.1)
				(type default)
			)
			(layer "B.Fab")
		)
		(fp_line
			(start -0.12065 -0.3048)
			(end -0.67945 -0.3048)
			(stroke
				(width 0.1)
				(type default)
			)
			(layer "B.Fab")
		)
		(fp_line
			(start -0.12065 -0.2794)
			(end -0.12065 -0.3048)
			(stroke
				(width 0.1)
				(type default)
			)
			(layer "B.Fab")
		)
		(fp_line
			(start -0.120396 0.2794)
			(end 0.12065 0.2794)
			(stroke
				(width 0.1)
				(type default)
			)
			(layer "B.Fab")
		)
		(fp_line
			(start -0.120396 0.3048)
			(end -0.120396 0.2794)
			(stroke
				(width 0.1)
				(type default)
			)
			(layer "B.Fab")
		)
		(fp_line
			(start 0.12065 -0.305054)
			(end 0.12065 -0.2794)
			(stroke
				(width 0.1)
				(type default)
			)
			(layer "B.Fab")
		)
		(fp_line
			(start 0.12065 -0.2794)
			(end -0.12065 -0.2794)
			(stroke
				(width 0.1)
				(type default)
			)
			(layer "B.Fab")
		)
		(fp_line
			(start 0.12065 0.2794)
			(end 0.12065 0.3048)
			(stroke
				(width 0.1)
				(type default)
			)
			(layer "B.Fab")
		)
		(fp_line
			(start 0.12065 0.3048)
			(end 0.67945 0.3048)
			(stroke
				(width 0.1)
				(type default)
			)
			(layer "B.Fab")
		)
		(fp_line
			(start 0.67945 -0.305054)
			(end 0.12065 -0.305054)
			(stroke
				(width 0.1)
				(type default)
			)
			(layer "B.Fab")
		)
		(fp_line
			(start 0.67945 0.3048)
			(end 0.67945 -0.305054)
			(stroke
				(width 0.1)
				(type default)
			)
			(layer "B.Fab")
		)
		(pad "1" smd circle
			(at 0.40005 0 180)
			(size 0 0)
			(layers "B.Cu" "B.Mask" "B.Paste")
			(net "P3V3_NIC3")
		)
		(pad "2" smd circle
			(at -0.40005 0 180)
			(size 0 0)
			(layers "B.Cu" "B.Mask" "B.Paste")
			(net "GND")
		)
	)
	(footprint ""
		(layer "B.Cu")
		(at 212.09 -192.405 -90)
		(property "Reference" "R1534"
			(at 0 0 90)
			(layer "B.SilkS")
			(hide yes)
			(effects
				(font
					(size 1.27 1.27)
				)
				(justify mirror)
			)
		)
		(property "Value" ""
			(at 0 0 90)
			(layer "B.Fab")
			(effects
				(font
					(size 1.27 1.27)
				)
				(justify mirror)
			)
		)
		(duplicate_pad_numbers_are_jumpers no)
		(fp_line
			(start -0.7874 0.4064)
			(end 0.7874 0.4064)
			(stroke
				(width 0.1524)
				(type default)
			)
			(layer "B.SilkS")
		)
		(fp_line
			(start 0.7874 0.4064)
			(end 0.7874 -0.4064)
			(stroke
				(width 0.1524)
				(type default)
			)
			(layer "B.SilkS")
		)
		(fp_line
			(start -0.7874 -0.4064)
			(end -0.7874 0.4064)
			(stroke
				(width 0.1524)
				(type default)
			)
			(layer "B.SilkS")
		)
		(fp_line
			(start 0.7874 -0.4064)
			(end -0.7874 -0.4064)
			(stroke
				(width 0.1524)
				(type default)
			)
			(layer "B.SilkS")
		)
		(fp_line
			(start -0.67945 0.3048)
			(end -0.120396 0.3048)
			(stroke
				(width 0.1)
				(type default)
			)
			(layer "B.Fab")
		)
		(fp_line
			(start -0.120396 0.3048)
			(end -0.120396 0.2794)
			(stroke
				(width 0.1)
				(type default)
			)
			(layer "B.Fab")
		)
		(fp_line
			(start 0.12065 0.3048)
			(end 0.67945 0.3048)
			(stroke
				(width 0.1)
				(type default)
			)
			(layer "B.Fab")
		)
		(fp_line
			(start 0.67945 0.3048)
			(end 0.67945 -0.305054)
			(stroke
				(width 0.1)
				(type default)
			)
			(layer "B.Fab")
		)
		(fp_line
			(start -0.120396 0.2794)
			(end 0.12065 0.2794)
			(stroke
				(width 0.1)
				(type default)
			)
			(layer "B.Fab")
		)
		(fp_line
			(start 0.12065 0.2794)
			(end 0.12065 0.3048)
			(stroke
				(width 0.1)
				(type default)
			)
			(layer "B.Fab")
		)
		(fp_line
			(start -0.12065 -0.2794)
			(end -0.12065 -0.3048)
			(stroke
				(width 0.1)
				(type default)
			)
			(layer "B.Fab")
		)
		(fp_line
			(start 0.12065 -0.2794)
			(end -0.12065 -0.2794)
			(stroke
				(width 0.1)
				(type default)
			)
			(layer "B.Fab")
		)
		(fp_line
			(start -0.67945 -0.3048)
			(end -0.67945 0.3048)
			(stroke
				(width 0.1)
				(type default)
			)
			(layer "B.Fab")
		)
		(fp_line
			(start -0.12065 -0.3048)
			(end -0.67945 -0.3048)
			(stroke
				(width 0.1)
				(type default)
			)
			(layer "B.Fab")
		)
		(fp_line
			(start 0.12065 -0.305054)
			(end 0.12065 -0.2794)
			(stroke
				(width 0.1)
				(type default)
			)
			(layer "B.Fab")
		)
		(fp_line
			(start 0.67945 -0.305054)
			(end 0.12065 -0.305054)
			(stroke
				(width 0.1)
				(type default)
			)
			(layer "B.Fab")
		)
		(pad "1" smd circle
			(at 0.40005 0 90)
			(size 0 0)
			(layers "B.Cu" "B.Mask" "B.Paste")
			(net "SMB_NIC7_LS_R_SCL")
		)
		(pad "2" smd circle
			(at -0.40005 0 90)
			(size 0 0)
			(layers "B.Cu" "B.Mask" "B.Paste")
			(net "SMB_NIC7_R_SCL")
		)
	)
	(footprint ""
		(layer "B.Cu")
		(at 109.463586 -83.715606 -90)
		(property "Reference" "C2667"
			(at 0 0 90)
			(layer "B.SilkS")
			(hide yes)
			(effects
				(font
					(size 1.27 1.27)
				)
				(justify mirror)
			)
		)
		(property "Value" ""
			(at 0 0 90)
			(layer "B.Fab")
			(effects
				(font
					(size 1.27 1.27)
				)
				(justify mirror)
			)
		)
		(duplicate_pad_numbers_are_jumpers no)
		(fp_line
			(start -0.7874 0.4064)
			(end 0.7874 0.4064)
			(stroke
				(width 0.1524)
				(type default)
			)
			(layer "B.SilkS")
		)
		(fp_line
			(start 0.7874 0.4064)
			(end 0.7874 -0.4064)
			(stroke
				(width 0.1524)
				(type default)
			)
			(layer "B.SilkS")
		)
		(fp_line
			(start -0.7874 -0.4064)
			(end -0.7874 0.4064)
			(stroke
				(width 0.1524)
				(type default)
			)
			(layer "B.SilkS")
		)
		(fp_line
			(start 0.7874 -0.4064)
			(end -0.7874 -0.4064)
			(stroke
				(width 0.1524)
				(type default)
			)
			(layer "B.SilkS")
		)
		(fp_line
			(start -0.67945 0.3048)
			(end -0.120396 0.3048)
			(stroke
				(width 0.1)
				(type default)
			)
			(layer "B.Fab")
		)
		(fp_line
			(start -0.120396 0.3048)
			(end -0.120396 0.2794)
			(stroke
				(width 0.1)
				(type default)
			)
			(layer "B.Fab")
		)
		(fp_line
			(start 0.12065 0.3048)
			(end 0.67945 0.3048)
			(stroke
				(width 0.1)
				(type default)
			)
			(layer "B.Fab")
		)
		(fp_line
			(start 0.67945 0.3048)
			(end 0.67945 -0.305054)
			(stroke
				(width 0.1)
				(type default)
			)
			(layer "B.Fab")
		)
		(fp_line
			(start -0.120396 0.2794)
			(end 0.12065 0.2794)
			(stroke
				(width 0.1)
				(type default)
			)
			(layer "B.Fab")
		)
		(fp_line
			(start 0.12065 0.2794)
			(end 0.12065 0.3048)
			(stroke
				(width 0.1)
				(type default)
			)
			(layer "B.Fab")
		)
		(fp_line
			(start -0.12065 -0.2794)
			(end -0.12065 -0.3048)
			(stroke
				(width 0.1)
				(type default)
			)
			(layer "B.Fab")
		)
		(fp_line
			(start 0.12065 -0.2794)
			(end -0.12065 -0.2794)
			(stroke
				(width 0.1)
				(type default)
			)
			(layer "B.Fab")
		)
		(fp_line
			(start -0.67945 -0.3048)
			(end -0.67945 0.3048)
			(stroke
				(width 0.1)
				(type default)
			)
			(layer "B.Fab")
		)
		(fp_line
			(start -0.12065 -0.3048)
			(end -0.67945 -0.3048)
			(stroke
				(width 0.1)
				(type default)
			)
			(layer "B.Fab")
		)
		(fp_line
			(start 0.12065 -0.305054)
			(end 0.12065 -0.2794)
			(stroke
				(width 0.1)
				(type default)
			)
			(layer "B.Fab")
		)
		(fp_line
			(start 0.67945 -0.305054)
			(end 0.12065 -0.305054)
			(stroke
				(width 0.1)
				(type default)
			)
			(layer "B.Fab")
		)
		(pad "1" smd circle
			(at 0.40005 0 90)
			(size 0 0)
			(layers "B.Cu" "B.Mask" "B.Paste")
			(net "P3V3_VDD_9ZXL0851_0_7")
		)
		(pad "2" smd circle
			(at -0.40005 0 90)
			(size 0 0)
			(layers "B.Cu" "B.Mask" "B.Paste")
			(net "GND")
		)
	)
	(footprint ""
		(layer "B.Cu")
		(at 55.849774 -303.499774 -90)
		(property "Reference" "C2913"
			(at 0 0 90)
			(layer "B.SilkS")
			(hide yes)
			(effects
				(font
					(size 1.27 1.27)
				)
				(justify mirror)
			)
		)
		(property "Value" ""
			(at 0 0 90)
			(layer "B.Fab")
			(effects
				(font
					(size 1.27 1.27)
				)
				(justify mirror)
			)
		)
		(duplicate_pad_numbers_are_jumpers no)
		(fp_line
			(start -0.299974 0.150114)
			(end 0.299974 0.150114)
			(stroke
				(width 0.1)
				(type default)
			)
			(layer "B.Fab")
		)
		(fp_line
			(start 0.299974 0.150114)
			(end 0.299974 -0.150114)
			(stroke
				(width 0.1)
				(type default)
			)
			(layer "B.Fab")
		)
		(fp_line
			(start -0.299974 -0.150114)
			(end -0.299974 0.150114)
			(stroke
				(width 0.1)
				(type default)
			)
			(layer "B.Fab")
		)
		(fp_line
			(start 0.299974 -0.150114)
			(end -0.299974 -0.150114)
			(stroke
				(width 0.1)
				(type default)
			)
			(layer "B.Fab")
		)
		(pad "1" smd rect
			(at 0.2667 0 90)
			(size 0.3048 0.381)
			(layers "B.Cu" "B.Mask" "B.Paste")
			(net "P1V25_PEX0")
		)
		(pad "2" smd rect
			(at -0.2667 0 90)
			(size 0.3048 0.381)
			(layers "B.Cu" "B.Mask" "B.Paste")
			(net "GND")
		)
	)
)
